(kicad_pcb
	(version 20260206)
	(generator "pcbnew")
	(generator_version "10.0")
	(general
		(thickness 1.6)
		(legacy_teardrops no)
	)
	(paper "A4")
	(title_block
		(title "9054_F0T_PDB_BD_GPU_F_V04_1213_1550_OCP.brd")
		(comment 1 "Grand Teton / footprints 34-39 of 608")
	)
	(layers
		(0 "F.Cu" signal "TOP")
		(4 "In1.Cu" signal "GND")
		(6 "In2.Cu" signal "IN1")
		(8 "In3.Cu" signal "GND1")
		(10 "In4.Cu" signal "VCC")
		(12 "In5.Cu" signal "VCC1")
		(14 "In6.Cu" signal "GND2")
		(16 "In7.Cu" signal "IN2")
		(18 "In8.Cu" signal "GND3")
		(2 "B.Cu" signal "BOTTOM")
		(9 "F.Adhes" user "F.Adhesive")
		(11 "B.Adhes" user "B.Adhesive")
		(13 "F.Paste" user "Package Geometry/Pastemask Top")
		(15 "B.Paste" user "Package Geometry/Pastemask Bottom")
		(5 "F.SilkS" user "Ref Des/Silkscreen Top")
		(7 "B.SilkS" user "Ref Des/Silkscreen Bottom")
		(1 "F.Mask" user "Board Geometry/Soldermask Top")
		(3 "B.Mask" user "Board Geometry/Soldermask Bottom")
		(17 "Dwgs.User" user "User.Drawings")
		(19 "Cmts.User" user "User.Comments")
		(21 "Eco1.User" user "User.Eco1")
		(23 "Eco2.User" user "User.Eco2")
		(25 "Edge.Cuts" user "Board Geometry/Outline")
		(27 "Margin" user)
		(31 "F.CrtYd" user "Package Geometry/Place Bound Top")
		(29 "B.CrtYd" user "Package Geometry/Place Bound Bottom")
		(35 "F.Fab" user "Ref Des/Assembly Top")
		(33 "B.Fab" user "Ref Des/Assembly Bottom")
	)
	(footprint ""
		(layer "F.Cu")
		(at 306.7304 -34.3662)
		(property "Reference" "PR6959"
			(at 0 0 0)
			(layer "F.SilkS")
			(hide yes)
			(effects
				(font
					(size 1.27 1.27)
				)
			)
		)
		(property "Value" ""
			(at 0 0 0)
			(layer "F.Fab")
			(effects
				(font
					(size 1.27 1.27)
				)
			)
		)
		(duplicate_pad_numbers_are_jumpers no)
		(fp_line
			(start -1.2954 -0.5842)
			(end 1.2954 -0.5842)
			(stroke
				(width 0.1524)
				(type default)
			)
			(layer "F.SilkS")
		)
		(fp_line
			(start -1.2954 0.5842)
			(end -1.2954 -0.5842)
			(stroke
				(width 0.1524)
				(type default)
			)
			(layer "F.SilkS")
		)
		(fp_line
			(start 1.2954 -0.5842)
			(end 1.2954 0.5842)
			(stroke
				(width 0.1524)
				(type default)
			)
			(layer "F.SilkS")
		)
		(fp_line
			(start 1.2954 0.5842)
			(end -1.2954 0.5842)
			(stroke
				(width 0.1524)
				(type default)
			)
			(layer "F.SilkS")
		)
		(fp_line
			(start -1.1938 -0.406654)
			(end -0.8636 -0.406654)
			(stroke
				(width 0.1)
				(type default)
			)
			(layer "F.Fab")
		)
		(fp_line
			(start -1.1938 0.4064)
			(end -1.1938 -0.406654)
			(stroke
				(width 0.1)
				(type default)
			)
			(layer "F.Fab")
		)
		(fp_line
			(start -0.8636 -0.4572)
			(end 0.8636 -0.4572)
			(stroke
				(width 0.1)
				(type default)
			)
			(layer "F.Fab")
		)
		(fp_line
			(start -0.8636 -0.406654)
			(end -0.8636 -0.4572)
			(stroke
				(width 0.1)
				(type default)
			)
			(layer "F.Fab")
		)
		(fp_line
			(start -0.8636 0.4064)
			(end -1.1938 0.4064)
			(stroke
				(width 0.1)
				(type default)
			)
			(layer "F.Fab")
		)
		(fp_line
			(start -0.8636 0.4318)
			(end -0.8636 0.4064)
			(stroke
				(width 0.1)
				(type default)
			)
			(layer "F.Fab")
		)
		(fp_line
			(start -0.8636 0.4572)
			(end -0.8636 0.4318)
			(stroke
				(width 0.1)
				(type default)
			)
			(layer "F.Fab")
		)
		(fp_line
			(start 0.8636 -0.4572)
			(end 0.8636 -0.406654)
			(stroke
				(width 0.1)
				(type default)
			)
			(layer "F.Fab")
		)
		(fp_line
			(start 0.8636 -0.406654)
			(end 1.1938 -0.406654)
			(stroke
				(width 0.1)
				(type default)
			)
			(layer "F.Fab")
		)
		(fp_line
			(start 0.8636 0.4064)
			(end 0.8636 0.4572)
			(stroke
				(width 0.1)
				(type default)
			)
			(layer "F.Fab")
		)
		(fp_line
			(start 0.8636 0.4572)
			(end -0.8636 0.4572)
			(stroke
				(width 0.1)
				(type default)
			)
			(layer "F.Fab")
		)
		(fp_line
			(start 1.1938 -0.406654)
			(end 1.1938 0.4064)
			(stroke
				(width 0.1)
				(type default)
			)
			(layer "F.Fab")
		)
		(fp_line
			(start 1.1938 0.4064)
			(end 0.8636 0.4064)
			(stroke
				(width 0.1)
				(type default)
			)
			(layer "F.Fab")
		)
		(pad "1" smd rect
			(at -0.7366 0 270)
			(size 0.7112 0.8128)
			(layers "F.Cu" "F.Mask" "F.Paste")
			(net "P52V_HS_1272_S_N")
		)
		(pad "2" smd rect
			(at 0.7366 0 270)
			(size 0.7112 0.8128)
			(layers "F.Cu" "F.Mask" "F.Paste")
			(net "P52V_HS1_SENSE_N_R2")
		)
	)
	(footprint ""
		(layer "F.Cu")
		(at 390.652 -25.273)
		(property "Reference" "PU3"
			(at -1.143 1.93167 0)
			(unlocked yes)
			(layer "F.SilkS")
			(effects
				(font
					(size 0.7874 0.5842)
					(thickness 0.1524)
				)
				(justify left)
			)
		)
		(property "Value" ""
			(at 0 0 0)
			(layer "F.Fab")
			(effects
				(font
					(size 1.27 1.27)
				)
			)
		)
		(duplicate_pad_numbers_are_jumpers no)
		(fp_line
			(start -1.335278 -1.100074)
			(end -1.335278 1.100074)
			(stroke
				(width 0.1524)
				(type default)
			)
			(layer "F.SilkS")
		)
		(fp_line
			(start -1.335278 1.100074)
			(end 1.335278 1.100074)
			(stroke
				(width 0.1524)
				(type default)
			)
			(layer "F.SilkS")
		)
		(fp_line
			(start 1.335278 -1.100074)
			(end -1.335278 -1.100074)
			(stroke
				(width 0.1524)
				(type default)
			)
			(layer "F.SilkS")
		)
		(fp_line
			(start 1.335278 1.100074)
			(end 1.335278 -1.100074)
			(stroke
				(width 0.1524)
				(type default)
			)
			(layer "F.SilkS")
		)
		(fp_line
			(start -0.674878 -1.100074)
			(end -0.674878 1.100074)
			(stroke
				(width 0.1)
				(type default)
			)
			(layer "F.Fab")
		)
		(fp_line
			(start -0.674878 1.100074)
			(end 0.674878 1.100074)
			(stroke
				(width 0.1)
				(type default)
			)
			(layer "F.Fab")
		)
		(fp_line
			(start 0.674878 -1.100074)
			(end -0.674878 -1.100074)
			(stroke
				(width 0.1)
				(type default)
			)
			(layer "F.Fab")
		)
		(fp_line
			(start 0.674878 1.100074)
			(end 0.674878 -1.100074)
			(stroke
				(width 0.1)
				(type default)
			)
			(layer "F.Fab")
		)
		(pad "D" smd rect
			(at 0.8001 0 270)
			(size 0.6096 0.8128)
			(layers "F.Cu" "F.Mask" "F.Paste")
			(net "P52V_HS1_EN_DISCHARGE_N")
		)
		(pad "G" smd rect
			(at -0.8001 -0.649986 270)
			(size 0.6096 0.8128)
			(layers "F.Cu" "F.Mask" "F.Paste")
			(net "P52V_HS1_EN_DISCHARGE")
		)
		(pad "S" smd rect
			(at -0.8001 0.649986 270)
			(size 0.6096 0.8128)
			(layers "F.Cu" "F.Mask" "F.Paste")
			(net "GND")
		)
	)
	(footprint ""
		(layer "F.Cu")
		(at 145.11782 -68.199)
		(property "Reference" "PR6985"
			(at 0 0 0)
			(layer "F.SilkS")
			(hide yes)
			(effects
				(font
					(size 1.27 1.27)
				)
			)
		)
		(property "Value" ""
			(at 0 0 0)
			(layer "F.Fab")
			(effects
				(font
					(size 1.27 1.27)
				)
			)
		)
		(duplicate_pad_numbers_are_jumpers no)
		(fp_line
			(start -1.2954 -0.5842)
			(end 1.2954 -0.5842)
			(stroke
				(width 0.1524)
				(type default)
			)
			(layer "F.SilkS")
		)
		(fp_line
			(start -1.2954 0.5842)
			(end -1.2954 -0.5842)
			(stroke
				(width 0.1524)
				(type default)
			)
			(layer "F.SilkS")
		)
		(fp_line
			(start 1.2954 -0.5842)
			(end 1.2954 0.5842)
			(stroke
				(width 0.1524)
				(type default)
			)
			(layer "F.SilkS")
		)
		(fp_line
			(start 1.2954 0.5842)
			(end -1.2954 0.5842)
			(stroke
				(width 0.1524)
				(type default)
			)
			(layer "F.SilkS")
		)
		(fp_line
			(start -1.1938 -0.406654)
			(end -0.8636 -0.406654)
			(stroke
				(width 0.1)
				(type default)
			)
			(layer "F.Fab")
		)
		(fp_line
			(start -1.1938 0.4064)
			(end -1.1938 -0.406654)
			(stroke
				(width 0.1)
				(type default)
			)
			(layer "F.Fab")
		)
		(fp_line
			(start -0.8636 -0.4572)
			(end 0.8636 -0.4572)
			(stroke
				(width 0.1)
				(type default)
			)
			(layer "F.Fab")
		)
		(fp_line
			(start -0.8636 -0.406654)
			(end -0.8636 -0.4572)
			(stroke
				(width 0.1)
				(type default)
			)
			(layer "F.Fab")
		)
		(fp_line
			(start -0.8636 0.4064)
			(end -1.1938 0.4064)
			(stroke
				(width 0.1)
				(type default)
			)
			(layer "F.Fab")
		)
		(fp_line
			(start -0.8636 0.4318)
			(end -0.8636 0.4064)
			(stroke
				(width 0.1)
				(type default)
			)
			(layer "F.Fab")
		)
		(fp_line
			(start -0.8636 0.4572)
			(end -0.8636 0.4318)
			(stroke
				(width 0.1)
				(type default)
			)
			(layer "F.Fab")
		)
		(fp_line
			(start 0.8636 -0.4572)
			(end 0.8636 -0.406654)
			(stroke
				(width 0.1)
				(type default)
			)
			(layer "F.Fab")
		)
		(fp_line
			(start 0.8636 -0.406654)
			(end 1.1938 -0.406654)
			(stroke
				(width 0.1)
				(type default)
			)
			(layer "F.Fab")
		)
		(fp_line
			(start 0.8636 0.4064)
			(end 0.8636 0.4572)
			(stroke
				(width 0.1)
				(type default)
			)
			(layer "F.Fab")
		)
		(fp_line
			(start 0.8636 0.4572)
			(end -0.8636 0.4572)
			(stroke
				(width 0.1)
				(type default)
			)
			(layer "F.Fab")
		)
		(fp_line
			(start 1.1938 -0.406654)
			(end 1.1938 0.4064)
			(stroke
				(width 0.1)
				(type default)
			)
			(layer "F.Fab")
		)
		(fp_line
			(start 1.1938 0.4064)
			(end 0.8636 0.4064)
			(stroke
				(width 0.1)
				(type default)
			)
			(layer "F.Fab")
		)
		(pad "1" smd rect
			(at -0.7366 0 270)
			(size 0.7112 0.8128)
			(layers "F.Cu" "F.Mask" "F.Paste")
			(net "P52V_HS2_1272_S_P")
		)
		(pad "2" smd rect
			(at 0.7366 0 270)
			(size 0.7112 0.8128)
			(layers "F.Cu" "F.Mask" "F.Paste")
			(net "P52V_HS2_SENSE_P_R1")
		)
	)
	(footprint ""
		(layer "F.Cu")
		(at 437.134 -37.211 90)
		(property "Reference" "R13"
			(at 0 0 90)
			(layer "F.SilkS")
			(hide yes)
			(effects
				(font
					(size 1.27 1.27)
				)
			)
		)
		(property "Value" ""
			(at 0 0 90)
			(layer "F.Fab")
			(effects
				(font
					(size 1.27 1.27)
				)
			)
		)
		(duplicate_pad_numbers_are_jumpers no)
		(fp_line
			(start 0.7874 -0.4064)
			(end 0.7874 0.4064)
			(stroke
				(width 0.1524)
				(type default)
			)
			(layer "F.SilkS")
		)
		(fp_line
			(start -0.7874 -0.4064)
			(end 0.7874 -0.4064)
			(stroke
				(width 0.1524)
				(type default)
			)
			(layer "F.SilkS")
		)
		(fp_line
			(start 0.7874 0.4064)
			(end -0.7874 0.4064)
			(stroke
				(width 0.1524)
				(type default)
			)
			(layer "F.SilkS")
		)
		(fp_line
			(start -0.7874 0.4064)
			(end -0.7874 -0.4064)
			(stroke
				(width 0.1524)
				(type default)
			)
			(layer "F.SilkS")
		)
		(fp_line
			(start -0.12065 -0.305054)
			(end -0.12065 -0.2794)
			(stroke
				(width 0.1)
				(type default)
			)
			(layer "F.Fab")
		)
		(fp_line
			(start -0.67945 -0.305054)
			(end -0.12065 -0.305054)
			(stroke
				(width 0.1)
				(type default)
			)
			(layer "F.Fab")
		)
		(fp_line
			(start 0.67945 -0.3048)
			(end 0.67945 0.3048)
			(stroke
				(width 0.1)
				(type default)
			)
			(layer "F.Fab")
		)
		(fp_line
			(start 0.12065 -0.3048)
			(end 0.67945 -0.3048)
			(stroke
				(width 0.1)
				(type default)
			)
			(layer "F.Fab")
		)
		(fp_line
			(start 0.12065 -0.2794)
			(end 0.12065 -0.3048)
			(stroke
				(width 0.1)
				(type default)
			)
			(layer "F.Fab")
		)
		(fp_line
			(start -0.12065 -0.2794)
			(end 0.12065 -0.2794)
			(stroke
				(width 0.1)
				(type default)
			)
			(layer "F.Fab")
		)
		(fp_line
			(start 0.120396 0.2794)
			(end -0.12065 0.2794)
			(stroke
				(width 0.1)
				(type default)
			)
			(layer "F.Fab")
		)
		(fp_line
			(start -0.12065 0.2794)
			(end -0.12065 0.3048)
			(stroke
				(width 0.1)
				(type default)
			)
			(layer "F.Fab")
		)
		(fp_line
			(start 0.67945 0.3048)
			(end 0.120396 0.3048)
			(stroke
				(width 0.1)
				(type default)
			)
			(layer "F.Fab")
		)
		(fp_line
			(start 0.120396 0.3048)
			(end 0.120396 0.2794)
			(stroke
				(width 0.1)
				(type default)
			)
			(layer "F.Fab")
		)
		(fp_line
			(start -0.12065 0.3048)
			(end -0.67945 0.3048)
			(stroke
				(width 0.1)
				(type default)
			)
			(layer "F.Fab")
		)
		(fp_line
			(start -0.67945 0.3048)
			(end -0.67945 -0.305054)
			(stroke
				(width 0.1)
				(type default)
			)
			(layer "F.Fab")
		)
		(pad "1" smd circle
			(at -0.40005 0 90)
			(size 0 0)
			(layers "F.Cu" "F.Mask" "F.Paste")
			(net "SMB_P52V_SCL")
		)
		(pad "2" smd circle
			(at 0.40005 0 90)
			(size 0 0)
			(layers "F.Cu" "F.Mask" "F.Paste")
			(net "SMB_P52V_PDB_SCL_R")
		)
	)
	(footprint ""
		(layer "F.Cu")
		(at 438.3278 -22.352 180)
		(property "Reference" "R64"
			(at 0 0 180)
			(layer "F.SilkS")
			(hide yes)
			(effects
				(font
					(size 1.27 1.27)
				)
			)
		)
		(property "Value" ""
			(at 0 0 180)
			(layer "F.Fab")
			(effects
				(font
					(size 1.27 1.27)
				)
			)
		)
		(duplicate_pad_numbers_are_jumpers no)
		(fp_line
			(start 0.7874 0.4064)
			(end -0.7874 0.4064)
			(stroke
				(width 0.1524)
				(type default)
			)
			(layer "F.SilkS")
		)
		(fp_line
			(start 0.7874 -0.4064)
			(end 0.7874 0.4064)
			(stroke
				(width 0.1524)
				(type default)
			)
			(layer "F.SilkS")
		)
		(fp_line
			(start -0.7874 0.4064)
			(end -0.7874 -0.4064)
			(stroke
				(width 0.1524)
				(type default)
			)
			(layer "F.SilkS")
		)
		(fp_line
			(start -0.7874 -0.4064)
			(end 0.7874 -0.4064)
			(stroke
				(width 0.1524)
				(type default)
			)
			(layer "F.SilkS")
		)
		(fp_line
			(start 0.67945 0.3048)
			(end 0.120396 0.3048)
			(stroke
				(width 0.1)
				(type default)
			)
			(layer "F.Fab")
		)
		(fp_line
			(start 0.67945 -0.3048)
			(end 0.67945 0.3048)
			(stroke
				(width 0.1)
				(type default)
			)
			(layer "F.Fab")
		)
		(fp_line
			(start 0.12065 -0.2794)
			(end 0.12065 -0.3048)
			(stroke
				(width 0.1)
				(type default)
			)
			(layer "F.Fab")
		)
		(fp_line
			(start 0.12065 -0.3048)
			(end 0.67945 -0.3048)
			(stroke
				(width 0.1)
				(type default)
			)
			(layer "F.Fab")
		)
		(fp_line
			(start 0.120396 0.3048)
			(end 0.120396 0.2794)
			(stroke
				(width 0.1)
				(type default)
			)
			(layer "F.Fab")
		)
		(fp_line
			(start 0.120396 0.2794)
			(end -0.12065 0.2794)
			(stroke
				(width 0.1)
				(type default)
			)
			(layer "F.Fab")
		)
		(fp_line
			(start -0.12065 0.3048)
			(end -0.67945 0.3048)
			(stroke
				(width 0.1)
				(type default)
			)
			(layer "F.Fab")
		)
		(fp_line
			(start -0.12065 0.2794)
			(end -0.12065 0.3048)
			(stroke
				(width 0.1)
				(type default)
			)
			(layer "F.Fab")
		)
		(fp_line
			(start -0.12065 -0.2794)
			(end 0.12065 -0.2794)
			(stroke
				(width 0.1)
				(type default)
			)
			(layer "F.Fab")
		)
		(fp_line
			(start -0.12065 -0.305054)
			(end -0.12065 -0.2794)
			(stroke
				(width 0.1)
				(type default)
			)
			(layer "F.Fab")
		)
		(fp_line
			(start -0.67945 0.3048)
			(end -0.67945 -0.305054)
			(stroke
				(width 0.1)
				(type default)
			)
			(layer "F.Fab")
		)
		(fp_line
			(start -0.67945 -0.305054)
			(end -0.12065 -0.305054)
			(stroke
				(width 0.1)
				(type default)
			)
			(layer "F.Fab")
		)
		(pad "1" smd circle
			(at -0.40005 0 180)
			(size 0 0)
			(layers "F.Cu" "F.Mask" "F.Paste")
			(net "GND")
		)
		(pad "2" smd circle
			(at 0.40005 0 180)
			(size 0 0)
			(layers "F.Cu" "F.Mask" "F.Paste")
			(net "FRU_ADDR2")
		)
	)
	(footprint ""
		(layer "F.Cu")
		(at 416.814 -51.562 90)
		(property "Reference" "R161"
			(at 0 0 90)
			(layer "F.SilkS")
			(hide yes)
			(effects
				(font
					(size 1.27 1.27)
				)
			)
		)
		(property "Value" ""
			(at 0 0 90)
			(layer "F.Fab")
			(effects
				(font
					(size 1.27 1.27)
				)
			)
		)
		(duplicate_pad_numbers_are_jumpers no)
		(fp_line
			(start 0.7874 -0.4064)
			(end 0.7874 0.4064)
			(stroke
				(width 0.1524)
				(type default)
			)
			(layer "F.SilkS")
		)
		(fp_line
			(start -0.7874 -0.4064)
			(end 0.7874 -0.4064)
			(stroke
				(width 0.1524)
				(type default)
			)
			(layer "F.SilkS")
		)
		(fp_line
			(start 0.7874 0.4064)
			(end -0.7874 0.4064)
			(stroke
				(width 0.1524)
				(type default)
			)
			(layer "F.SilkS")
		)
		(fp_line
			(start -0.7874 0.4064)
			(end -0.7874 -0.4064)
			(stroke
				(width 0.1524)
				(type default)
			)
			(layer "F.SilkS")
		)
		(fp_line
			(start -0.12065 -0.305054)
			(end -0.12065 -0.2794)
			(stroke
				(width 0.1)
				(type default)
			)
			(layer "F.Fab")
		)
		(fp_line
			(start -0.67945 -0.305054)
			(end -0.12065 -0.305054)
			(stroke
				(width 0.1)
				(type default)
			)
			(layer "F.Fab")
		)
		(fp_line
			(start 0.67945 -0.3048)
			(end 0.67945 0.3048)
			(stroke
				(width 0.1)
				(type default)
			)
			(layer "F.Fab")
		)
		(fp_line
			(start 0.12065 -0.3048)
			(end 0.67945 -0.3048)
			(stroke
				(width 0.1)
				(type default)
			)
			(layer "F.Fab")
		)
		(fp_line
			(start 0.12065 -0.2794)
			(end 0.12065 -0.3048)
			(stroke
				(width 0.1)
				(type default)
			)
			(layer "F.Fab")
		)
		(fp_line
			(start -0.12065 -0.2794)
			(end 0.12065 -0.2794)
			(stroke
				(width 0.1)
				(type default)
			)
			(layer "F.Fab")
		)
		(fp_line
			(start 0.120396 0.2794)
			(end -0.12065 0.2794)
			(stroke
				(width 0.1)
				(type default)
			)
			(layer "F.Fab")
		)
		(fp_line
			(start -0.12065 0.2794)
			(end -0.12065 0.3048)
			(stroke
				(width 0.1)
				(type default)
			)
			(layer "F.Fab")
		)
		(fp_line
			(start 0.67945 0.3048)
			(end 0.120396 0.3048)
			(stroke
				(width 0.1)
				(type default)
			)
			(layer "F.Fab")
		)
		(fp_line
			(start 0.120396 0.3048)
			(end 0.120396 0.2794)
			(stroke
				(width 0.1)
				(type default)
			)
			(layer "F.Fab")
		)
		(fp_line
			(start -0.12065 0.3048)
			(end -0.67945 0.3048)
			(stroke
				(width 0.1)
				(type default)
			)
			(layer "F.Fab")
		)
		(fp_line
			(start -0.67945 0.3048)
			(end -0.67945 -0.305054)
			(stroke
				(width 0.1)
				(type default)
			)
			(layer "F.Fab")
		)
		(pad "1" smd circle
			(at -0.40005 0 90)
			(size 0 0)
			(layers "F.Cu" "F.Mask" "F.Paste")
			(net "PWRGD_P52V_HS1_4287_PG_R_N")
		)
		(pad "2" smd circle
			(at 0.40005 0 90)
			(size 0 0)
			(layers "F.Cu" "F.Mask" "F.Paste")
			(net "GND")
		)
	)
)
